# T6G (Grand Teton) — schematic netlist excerpt (pin names and nets, part order shuffled) for the footprints in the layout excerpt that follows; sources: Cadence DE-HDL packaged netlist, KiCad conversion of 04192023_DAF0TMB3IC0_F0TG_MB_C_brd_V02_OCP.brd

PC255_2  Q_CAP  0.1UF 25V 10% X7R  pkg 0402  page 211 : A = PVDDCR_CPU0_P1_VCCS ; B = GND
R1008  Q_RES  0 5% EMPTY  pkg 0402LF  page 290 : A = P1V8_CPU0_RT_1D ; B = P1V8_CPU0_RT1_1A_1D

(kicad_pcb
	(version 20260206)
	(generator "pcbnew")
	(generator_version "10.0")
	(general
		(thickness 1.6)
		(legacy_teardrops no)
	)
	(paper "A4")
	(title_block
		(title "04192023_DAF0TMB3IC0_F0TG_MB_C_brd_V02_OCP.brd")
		(comment 1 "Grand Teton / footprints 4818-4819 of 8354")
	)
	(layers
		(0 "F.Cu" signal "TOP")
		(4 "In1.Cu" signal "GND")
		(6 "In2.Cu" signal "IN1")
		(8 "In3.Cu" signal "GND1")
		(10 "In4.Cu" signal "IN2")
		(12 "In5.Cu" signal "GND2")
		(14 "In6.Cu" signal "IN3")
		(16 "In7.Cu" signal "GND3")
		(18 "In8.Cu" signal "VCC")
		(20 "In9.Cu" signal "VCC1")
		(22 "In10.Cu" signal "GND4")
		(24 "In11.Cu" signal "IN4")
		(26 "In12.Cu" signal "GND5")
		(28 "In13.Cu" signal "IN5")
		(30 "In14.Cu" signal "GND6")
		(32 "In15.Cu" signal "IN6")
		(34 "In16.Cu" signal "GND7")
		(2 "B.Cu" signal "BOTTOM")
		(9 "F.Adhes" user "F.Adhesive")
		(11 "B.Adhes" user "B.Adhesive")
		(13 "F.Paste" user "Package Geometry/Pastemask Top")
		(15 "B.Paste" user "Package Geometry/Pastemask Bottom")
		(5 "F.SilkS" user "Ref Des/Silkscreen Top")
		(7 "B.SilkS" user "Ref Des/Silkscreen Bottom")
		(1 "F.Mask" user "Board Geometry/Soldermask Top")
		(3 "B.Mask" user "Board Geometry/Soldermask Bottom")
		(17 "Dwgs.User" user "User.Drawings")
		(19 "Cmts.User" user "User.Comments")
		(21 "Eco1.User" user "User.Eco1")
		(23 "Eco2.User" user "User.Eco2")
		(25 "Edge.Cuts" user "Board Geometry/Outline")
		(27 "Margin" user)
		(31 "F.CrtYd" user "Package Geometry/Place Bound Top")
		(29 "B.CrtYd" user "Package Geometry/Place Bound Bottom")
		(35 "F.Fab" user "Ref Des/Assembly Top")
		(33 "B.Fab" user "Ref Des/Assembly Bottom")
	)
	(footprint ""
		(layer "F.Cu")
		(at 93.375734 -177.818288 -90)
		(property "Reference" "PC255_2"
			(at 0 0 270)
			(layer "F.SilkS")
			(hide yes)
			(effects
				(font
					(size 1.27 1.27)
				)
			)
		)
		(property "Value" ""
			(at 0 0 270)
			(layer "F.Fab")
			(effects
				(font
					(size 1.27 1.27)
				)
			)
		)
		(duplicate_pad_numbers_are_jumpers no)
		(fp_line
			(start -0.7874 0.4064)
			(end -0.7874 -0.4064)
			(stroke
				(width 0.1524)
				(type default)
			)
			(layer "F.SilkS")
		)
		(fp_line
			(start 0.7874 0.4064)
			(end -0.7874 0.4064)
			(stroke
				(width 0.1524)
				(type default)
			)
			(layer "F.SilkS")
		)
		(fp_line
			(start -0.7874 -0.4064)
			(end 0.7874 -0.4064)
			(stroke
				(width 0.1524)
				(type default)
			)
			(layer "F.SilkS")
		)
		(fp_line
			(start 0.7874 -0.4064)
			(end 0.7874 0.4064)
			(stroke
				(width 0.1524)
				(type default)
			)
			(layer "F.SilkS")
		)
		(fp_line
			(start -0.67945 0.3048)
			(end -0.67945 -0.305054)
			(stroke
				(width 0.1)
				(type default)
			)
			(layer "F.Fab")
		)
		(fp_line
			(start -0.12065 0.3048)
			(end -0.67945 0.3048)
			(stroke
				(width 0.1)
				(type default)
			)
			(layer "F.Fab")
		)
		(fp_line
			(start 0.120396 0.3048)
			(end 0.120396 0.2794)
			(stroke
				(width 0.1)
				(type default)
			)
			(layer "F.Fab")
		)
		(fp_line
			(start 0.67945 0.3048)
			(end 0.120396 0.3048)
			(stroke
				(width 0.1)
				(type default)
			)
			(layer "F.Fab")
		)
		(fp_line
			(start -0.12065 0.2794)
			(end -0.12065 0.3048)
			(stroke
				(width 0.1)
				(type default)
			)
			(layer "F.Fab")
		)
		(fp_line
			(start 0.120396 0.2794)
			(end -0.12065 0.2794)
			(stroke
				(width 0.1)
				(type default)
			)
			(layer "F.Fab")
		)
		(fp_line
			(start -0.12065 -0.2794)
			(end 0.12065 -0.2794)
			(stroke
				(width 0.1)
				(type default)
			)
			(layer "F.Fab")
		)
		(fp_line
			(start 0.12065 -0.2794)
			(end 0.12065 -0.3048)
			(stroke
				(width 0.1)
				(type default)
			)
			(layer "F.Fab")
		)
		(fp_line
			(start 0.12065 -0.3048)
			(end 0.67945 -0.3048)
			(stroke
				(width 0.1)
				(type default)
			)
			(layer "F.Fab")
		)
		(fp_line
			(start 0.67945 -0.3048)
			(end 0.67945 0.3048)
			(stroke
				(width 0.1)
				(type default)
			)
			(layer "F.Fab")
		)
		(fp_line
			(start -0.67945 -0.305054)
			(end -0.12065 -0.305054)
			(stroke
				(width 0.1)
				(type default)
			)
			(layer "F.Fab")
		)
		(fp_line
			(start -0.12065 -0.305054)
			(end -0.12065 -0.2794)
			(stroke
				(width 0.1)
				(type default)
			)
			(layer "F.Fab")
		)
		(pad "1" smd circle
			(at -0.40005 0 270)
			(size 0 0)
			(layers "F.Cu" "F.Mask" "F.Paste")
			(net "PVDDCR_CPU0_P1_VCCS")
		)
		(pad "2" smd circle
			(at 0.40005 0 270)
			(size 0 0)
			(layers "F.Cu" "F.Mask" "F.Paste")
			(net "GND")
		)
	)
	(footprint ""
		(layer "F.Cu")
		(at 359.190036 -392.48588 180)
		(property "Reference" "R1008"
			(at 0 0 180)
			(layer "F.SilkS")
			(hide yes)
			(effects
				(font
					(size 1.27 1.27)
				)
			)
		)
		(property "Value" ""
			(at 0 0 180)
			(layer "F.Fab")
			(effects
				(font
					(size 1.27 1.27)
				)
			)
		)
		(duplicate_pad_numbers_are_jumpers no)
		(fp_line
			(start 0.7874 0.4064)
			(end -0.7874 0.4064)
			(stroke
				(width 0.1524)
				(type default)
			)
			(layer "F.SilkS")
		)
		(fp_line
			(start 0.7874 -0.4064)
			(end 0.7874 0.4064)
			(stroke
				(width 0.1524)
				(type default)
			)
			(layer "F.SilkS")
		)
		(fp_line
			(start -0.7874 0.4064)
			(end -0.7874 -0.4064)
			(stroke
				(width 0.1524)
				(type default)
			)
			(layer "F.SilkS")
		)
		(fp_line
			(start -0.7874 -0.4064)
			(end 0.7874 -0.4064)
			(stroke
				(width 0.1524)
				(type default)
			)
			(layer "F.SilkS")
		)
		(fp_line
			(start 0.67945 0.3048)
			(end 0.120396 0.3048)
			(stroke
				(width 0.1)
				(type default)
			)
			(layer "F.Fab")
		)
		(fp_line
			(start 0.67945 -0.3048)
			(end 0.67945 0.3048)
			(stroke
				(width 0.1)
				(type default)
			)
			(layer "F.Fab")
		)
		(fp_line
			(start 0.12065 -0.2794)
			(end 0.12065 -0.3048)
			(stroke
				(width 0.1)
				(type default)
			)
			(layer "F.Fab")
		)
		(fp_line
			(start 0.12065 -0.3048)
			(end 0.67945 -0.3048)
			(stroke
				(width 0.1)
				(type default)
			)
			(layer "F.Fab")
		)
		(fp_line
			(start 0.120396 0.3048)
			(end 0.120396 0.2794)
			(stroke
				(width 0.1)
				(type default)
			)
			(layer "F.Fab")
		)
		(fp_line
			(start 0.120396 0.2794)
			(end -0.12065 0.2794)
			(stroke
				(width 0.1)
				(type default)
			)
			(layer "F.Fab")
		)
		(fp_line
			(start -0.12065 0.3048)
			(end -0.67945 0.3048)
			(stroke
				(width 0.1)
				(type default)
			)
			(layer "F.Fab")
		)
		(fp_line
			(start -0.12065 0.2794)
			(end -0.12065 0.3048)
			(stroke
				(width 0.1)
				(type default)
			)
			(layer "F.Fab")
		)
		(fp_line
			(start -0.12065 -0.2794)
			(end 0.12065 -0.2794)
			(stroke
				(width 0.1)
				(type default)
			)
			(layer "F.Fab")
		)
		(fp_line
			(start -0.12065 -0.305054)
			(end -0.12065 -0.2794)
			(stroke
				(width 0.1)
				(type default)
			)
			(layer "F.Fab")
		)
		(fp_line
			(start -0.67945 0.3048)
			(end -0.67945 -0.305054)
			(stroke
				(width 0.1)
				(type default)
			)
			(layer "F.Fab")
		)
		(fp_line
			(start -0.67945 -0.305054)
			(end -0.12065 -0.305054)
			(stroke
				(width 0.1)
				(type default)
			)
			(layer "F.Fab")
		)
		(pad "1" smd rect
			(at -0.40005 0)
			(size 0.4572 0.508)
			(layers "F.Cu" "F.Mask" "F.Paste")
			(net "P1V8_CPU0_RT_1D")
		)
		(pad "2" smd rect
			(at 0.40005 0)
			(size 0.4572 0.508)
			(layers "F.Cu" "F.Mask" "F.Paste")
			(net "P1V8_CPU0_RT1_1A_1D")
		)
	)
)
